# T6G (Grand Teton) — schematic netlist excerpt (pin names and nets, part order shuffled) for the footprints in the layout excerpt that follows; sources: Cadence DE-HDL packaged netlist, KiCad conversion of 04192023_DAF0TMB3IC0_F0TG_MB_C_brd_V02_OCP.brd

PR498  Q_RES  1.5 1% EMPTY  pkg 0402LF  page 195 : A = SW_PVDDCR_CPU0_P0_SW3_RC ; B = GND
R1779  Q_RES  100 1% CHIP  pkg 0402LF  page 187 : A = CLR_CMOS_N ; B = P1V5_BAT

(kicad_pcb
	(version 20260206)
	(generator "pcbnew")
	(generator_version "10.0")
	(general
		(thickness 1.6)
		(legacy_teardrops no)
	)
	(paper "A4")
	(title_block
		(title "04192023_DAF0TMB3IC0_F0TG_MB_C_brd_V02_OCP.brd")
		(comment 1 "Grand Teton / footprints 4786-4787 of 8354")
	)
	(layers
		(0 "F.Cu" signal "TOP")
		(4 "In1.Cu" signal "GND")
		(6 "In2.Cu" signal "IN1")
		(8 "In3.Cu" signal "GND1")
		(10 "In4.Cu" signal "IN2")
		(12 "In5.Cu" signal "GND2")
		(14 "In6.Cu" signal "IN3")
		(16 "In7.Cu" signal "GND3")
		(18 "In8.Cu" signal "VCC")
		(20 "In9.Cu" signal "VCC1")
		(22 "In10.Cu" signal "GND4")
		(24 "In11.Cu" signal "IN4")
		(26 "In12.Cu" signal "GND5")
		(28 "In13.Cu" signal "IN5")
		(30 "In14.Cu" signal "GND6")
		(32 "In15.Cu" signal "IN6")
		(34 "In16.Cu" signal "GND7")
		(2 "B.Cu" signal "BOTTOM")
		(9 "F.Adhes" user "F.Adhesive")
		(11 "B.Adhes" user "B.Adhesive")
		(13 "F.Paste" user "Package Geometry/Pastemask Top")
		(15 "B.Paste" user "Package Geometry/Pastemask Bottom")
		(5 "F.SilkS" user "Ref Des/Silkscreen Top")
		(7 "B.SilkS" user "Ref Des/Silkscreen Bottom")
		(1 "F.Mask" user "Board Geometry/Soldermask Top")
		(3 "B.Mask" user "Board Geometry/Soldermask Bottom")
		(17 "Dwgs.User" user "User.Drawings")
		(19 "Cmts.User" user "User.Comments")
		(21 "Eco1.User" user "User.Eco1")
		(23 "Eco2.User" user "User.Eco2")
		(25 "Edge.Cuts" user "Board Geometry/Outline")
		(27 "Margin" user)
		(31 "F.CrtYd" user "Package Geometry/Place Bound Top")
		(29 "B.CrtYd" user "Package Geometry/Place Bound Bottom")
		(35 "F.Fab" user "Ref Des/Assembly Top")
		(33 "B.Fab" user "Ref Des/Assembly Bottom")
	)
	(footprint ""
		(layer "F.Cu")
		(at 303.653952 -22.7457 90)
		(property "Reference" "R1779"
			(at 0 0 90)
			(layer "F.SilkS")
			(hide yes)
			(effects
				(font
					(size 1.27 1.27)
				)
			)
		)
		(property "Value" ""
			(at 0 0 90)
			(layer "F.Fab")
			(effects
				(font
					(size 1.27 1.27)
				)
			)
		)
		(duplicate_pad_numbers_are_jumpers no)
		(fp_line
			(start 0.7874 -0.4064)
			(end 0.7874 0.4064)
			(stroke
				(width 0.1524)
				(type default)
			)
			(layer "F.SilkS")
		)
		(fp_line
			(start -0.7874 -0.4064)
			(end 0.7874 -0.4064)
			(stroke
				(width 0.1524)
				(type default)
			)
			(layer "F.SilkS")
		)
		(fp_line
			(start 0.7874 0.4064)
			(end -0.7874 0.4064)
			(stroke
				(width 0.1524)
				(type default)
			)
			(layer "F.SilkS")
		)
		(fp_line
			(start -0.7874 0.4064)
			(end -0.7874 -0.4064)
			(stroke
				(width 0.1524)
				(type default)
			)
			(layer "F.SilkS")
		)
		(fp_line
			(start -0.12065 -0.305054)
			(end -0.12065 -0.2794)
			(stroke
				(width 0.1)
				(type default)
			)
			(layer "F.Fab")
		)
		(fp_line
			(start -0.67945 -0.305054)
			(end -0.12065 -0.305054)
			(stroke
				(width 0.1)
				(type default)
			)
			(layer "F.Fab")
		)
		(fp_line
			(start 0.67945 -0.3048)
			(end 0.67945 0.3048)
			(stroke
				(width 0.1)
				(type default)
			)
			(layer "F.Fab")
		)
		(fp_line
			(start 0.12065 -0.3048)
			(end 0.67945 -0.3048)
			(stroke
				(width 0.1)
				(type default)
			)
			(layer "F.Fab")
		)
		(fp_line
			(start 0.12065 -0.2794)
			(end 0.12065 -0.3048)
			(stroke
				(width 0.1)
				(type default)
			)
			(layer "F.Fab")
		)
		(fp_line
			(start -0.12065 -0.2794)
			(end 0.12065 -0.2794)
			(stroke
				(width 0.1)
				(type default)
			)
			(layer "F.Fab")
		)
		(fp_line
			(start 0.120396 0.2794)
			(end -0.12065 0.2794)
			(stroke
				(width 0.1)
				(type default)
			)
			(layer "F.Fab")
		)
		(fp_line
			(start -0.12065 0.2794)
			(end -0.12065 0.3048)
			(stroke
				(width 0.1)
				(type default)
			)
			(layer "F.Fab")
		)
		(fp_line
			(start 0.67945 0.3048)
			(end 0.120396 0.3048)
			(stroke
				(width 0.1)
				(type default)
			)
			(layer "F.Fab")
		)
		(fp_line
			(start 0.120396 0.3048)
			(end 0.120396 0.2794)
			(stroke
				(width 0.1)
				(type default)
			)
			(layer "F.Fab")
		)
		(fp_line
			(start -0.12065 0.3048)
			(end -0.67945 0.3048)
			(stroke
				(width 0.1)
				(type default)
			)
			(layer "F.Fab")
		)
		(fp_line
			(start -0.67945 0.3048)
			(end -0.67945 -0.305054)
			(stroke
				(width 0.1)
				(type default)
			)
			(layer "F.Fab")
		)
		(pad "1" smd circle
			(at -0.40005 0 90)
			(size 0 0)
			(layers "F.Cu" "F.Mask" "F.Paste")
			(net "CLR_CMOS_N")
		)
		(pad "2" smd circle
			(at 0.40005 0 90)
			(size 0 0)
			(layers "F.Cu" "F.Mask" "F.Paste")
			(net "P1V5_BAT")
		)
	)
	(footprint ""
		(layer "F.Cu")
		(at 384.755136 -184.478168 -90)
		(property "Reference" "PR498"
			(at 0 0 270)
			(layer "F.SilkS")
			(hide yes)
			(effects
				(font
					(size 1.27 1.27)
				)
			)
		)
		(property "Value" ""
			(at 0 0 270)
			(layer "F.Fab")
			(effects
				(font
					(size 1.27 1.27)
				)
			)
		)
		(duplicate_pad_numbers_are_jumpers no)
		(fp_line
			(start -0.7874 0.4064)
			(end -0.7874 -0.4064)
			(stroke
				(width 0.1524)
				(type default)
			)
			(layer "F.SilkS")
		)
		(fp_line
			(start 0.7874 0.4064)
			(end -0.7874 0.4064)
			(stroke
				(width 0.1524)
				(type default)
			)
			(layer "F.SilkS")
		)
		(fp_line
			(start -0.7874 -0.4064)
			(end 0.7874 -0.4064)
			(stroke
				(width 0.1524)
				(type default)
			)
			(layer "F.SilkS")
		)
		(fp_line
			(start 0.7874 -0.4064)
			(end 0.7874 0.4064)
			(stroke
				(width 0.1524)
				(type default)
			)
			(layer "F.SilkS")
		)
		(fp_line
			(start -0.67945 0.3048)
			(end -0.67945 -0.305054)
			(stroke
				(width 0.1)
				(type default)
			)
			(layer "F.Fab")
		)
		(fp_line
			(start -0.12065 0.3048)
			(end -0.67945 0.3048)
			(stroke
				(width 0.1)
				(type default)
			)
			(layer "F.Fab")
		)
		(fp_line
			(start 0.120396 0.3048)
			(end 0.120396 0.2794)
			(stroke
				(width 0.1)
				(type default)
			)
			(layer "F.Fab")
		)
		(fp_line
			(start 0.67945 0.3048)
			(end 0.120396 0.3048)
			(stroke
				(width 0.1)
				(type default)
			)
			(layer "F.Fab")
		)
		(fp_line
			(start -0.12065 0.2794)
			(end -0.12065 0.3048)
			(stroke
				(width 0.1)
				(type default)
			)
			(layer "F.Fab")
		)
		(fp_line
			(start 0.120396 0.2794)
			(end -0.12065 0.2794)
			(stroke
				(width 0.1)
				(type default)
			)
			(layer "F.Fab")
		)
		(fp_line
			(start -0.12065 -0.2794)
			(end 0.12065 -0.2794)
			(stroke
				(width 0.1)
				(type default)
			)
			(layer "F.Fab")
		)
		(fp_line
			(start 0.12065 -0.2794)
			(end 0.12065 -0.3048)
			(stroke
				(width 0.1)
				(type default)
			)
			(layer "F.Fab")
		)
		(fp_line
			(start 0.12065 -0.3048)
			(end 0.67945 -0.3048)
			(stroke
				(width 0.1)
				(type default)
			)
			(layer "F.Fab")
		)
		(fp_line
			(start 0.67945 -0.3048)
			(end 0.67945 0.3048)
			(stroke
				(width 0.1)
				(type default)
			)
			(layer "F.Fab")
		)
		(fp_line
			(start -0.67945 -0.305054)
			(end -0.12065 -0.305054)
			(stroke
				(width 0.1)
				(type default)
			)
			(layer "F.Fab")
		)
		(fp_line
			(start -0.12065 -0.305054)
			(end -0.12065 -0.2794)
			(stroke
				(width 0.1)
				(type default)
			)
			(layer "F.Fab")
		)
		(pad "1" smd circle
			(at -0.40005 0 270)
			(size 0 0)
			(layers "F.Cu" "F.Mask" "F.Paste")
			(net "SW_PVDDCR_CPU0_P0_SW3_RC")
		)
		(pad "2" smd circle
			(at 0.40005 0 270)
			(size 0 0)
			(layers "F.Cu" "F.Mask" "F.Paste")
			(net "GND")
		)
	)
)
